# lpddr4-test-board — KiCad project settings (.kicad_pro: net classes, design rules, text variables)
{
  "board": {
    "3dviewports": [],
    "design_settings": {
      "defaults": {
        "apply_defaults_to_fp_fields": false,
        "apply_defaults_to_fp_shapes": false,
        "apply_defaults_to_fp_text": false,
        "board_outline_line_width": 0.1,
        "copper_line_width": 0.2,
        "copper_text_italic": false,
        "copper_text_size_h": 1.5,
        "copper_text_size_v": 1.5,
        "copper_text_thickness": 0.3,
        "copper_text_upright": false,
        "courtyard_line_width": 0.05,
        "dimension_precision": 4,
        "dimension_units": 3,
        "dimensions": {
          "arrow_length": 1270000,
          "extension_offset": 500000,
          "keep_text_aligned": true,
          "suppress_zeroes": false,
          "text_position": 0,
          "units_format": 1
        },
        "fab_line_width": 0.1,
        "fab_text_italic": false,
        "fab_text_size_h": 1.0,
        "fab_text_size_v": 1.0,
        "fab_text_thickness": 0.15,
        "fab_text_upright": false,
        "other_line_width": 0.1,
        "other_text_italic": false,
        "other_text_size_h": 1.0,
        "other_text_size_v": 1.0,
        "other_text_thickness": 0.15,
        "other_text_upright": false,
        "pads": {
          "drill": 0.0,
          "height": 0.51,
          "width": 0.51
        },
        "silk_line_width": 0.15,
        "silk_text_italic": false,
        "silk_text_size_h": 0.7,
        "silk_text_size_v": 0.7,
        "silk_text_thickness": 0.15,
        "silk_text_upright": false,
        "zones": {
          "45_degree_only": false,
          "min_clearance": 0.15
        }
      },
      "diff_pair_dimensions": [
        {
          "gap": 0.0,
          "via_gap": 0.0,
          "width": 0.0
        }
      ],
      "drc_exclusions": [],
      "meta": {
        "filename": "board_design_settings.json",
        "version": 2
      },
      "rule_severities": {
        "annular_width": "error",
        "clearance": "error",
        "connection_width": "warning",
        "copper_edge_clearance": "error",
        "copper_sliver": "warning",
        "courtyards_overlap": "error",
        "creepage": "error",
        "diff_pair_gap_out_of_range": "error",
        "diff_pair_uncoupled_length_too_long": "error",
        "drill_out_of_range": "error",
        "duplicate_footprints": "warning",
        "extra_footprint": "warning",
        "footprint": "error",
        "footprint_filters_mismatch": "ignore",
        "footprint_symbol_mismatch": "warning",
        "footprint_type_mismatch": "ignore",
        "hole_clearance": "error",
        "hole_near_hole": "error",
        "hole_to_hole": "error",
        "holes_co_located": "warning",
        "invalid_outline": "error",
        "isolated_copper": "warning",
        "item_on_disabled_layer": "error",
        "items_not_allowed": "error",
        "length_out_of_range": "error",
        "lib_footprint_issues": "warning",
        "lib_footprint_mismatch": "warning",
        "malformed_courtyard": "error",
        "microvia_drill_out_of_range": "error",
        "mirrored_text_on_front_layer": "warning",
        "missing_courtyard": "ignore",
        "missing_footprint": "warning",
        "net_conflict": "warning",
        "nonmirrored_text_on_back_layer": "warning",
        "npth_inside_courtyard": "ignore",
        "padstack": "error",
        "pth_inside_courtyard": "ignore",
        "shorting_items": "error",
        "silk_edge_clearance": "warning",
        "silk_over_copper": "ignore",
        "silk_overlap": "ignore",
        "skew_out_of_range": "error",
        "solder_mask_bridge": "error",
        "starved_thermal": "error",
        "text_height": "warning",
        "text_on_edge_cuts": "error",
        "text_thickness": "warning",
        "through_hole_pad_without_hole": "error",
        "too_many_vias": "error",
        "track_angle": "error",
        "track_dangling": "warning",
        "track_segment_length": "error",
        "track_width": "error",
        "tracks_crossing": "error",
        "unconnected_items": "error",
        "unresolved_variable": "error",
        "via_dangling": "warning",
        "zones_intersect": "error"
      },
      "rule_severitieslegacy_courtyards_overlap": true,
      "rule_severitieslegacy_no_courtyard_defined": false,
      "rules": {
        "allow_blind_buried_vias": true,
        "allow_microvias": false,
        "max_error": 0.005,
        "min_clearance": 0.1,
        "min_connection": 0.0,
        "min_copper_edge_clearance": 0.05,
        "min_groove_width": 0.0,
        "min_hole_clearance": 0.25,
        "min_hole_to_hole": 0.25,
        "min_microvia_diameter": 0.2,
        "min_microvia_drill": 0.1,
        "min_resolved_spokes": 2,
        "min_silk_clearance": 0.0,
        "min_text_height": 0.8,
        "min_text_thickness": 0.08,
        "min_through_hole_diameter": 0.15,
        "min_track_width": 0.1,
        "min_via_annular_width": 0.05,
        "min_via_diameter": 0.45,
        "solder_mask_to_copper_clearance": 0.0,
        "use_height_for_length_calcs": true
      },
      "teardrop_options": [
        {
          "td_onpthpad": true,
          "td_onroundshapesonly": false,
          "td_onsmdpad": true,
          "td_ontrackend": false,
          "td_onvia": true
        }
      ],
      "teardrop_parameters": [
        {
          "td_allow_use_two_tracks": true,
          "td_curve_segcount": 1,
          "td_height_ratio": 1.0,
          "td_length_ratio": 0.5,
          "td_maxheight": 2.0,
          "td_maxlen": 1.0,
          "td_on_pad_in_zone": false,
          "td_target_name": "td_round_shape",
          "td_width_to_size_filter_ratio": 0.9
        },
        {
          "td_allow_use_two_tracks": true,
          "td_curve_segcount": 1,
          "td_height_ratio": 1.0,
          "td_length_ratio": 0.5,
          "td_maxheight": 2.0,
          "td_maxlen": 1.0,
          "td_on_pad_in_zone": false,
          "td_target_name": "td_rect_shape",
          "td_width_to_size_filter_ratio": 0.9
        },
        {
          "td_allow_use_two_tracks": true,
          "td_curve_segcount": 1,
          "td_height_ratio": 1.0,
          "td_length_ratio": 0.5,
          "td_maxheight": 2.0,
          "td_maxlen": 1.0,
          "td_on_pad_in_zone": false,
          "td_target_name": "td_track_end",
          "td_width_to_size_filter_ratio": 0.9
        }
      ],
      "track_widths": [
        0.0,
        0.125,
        0.15,
        0.2,
        0.4,
        0.5,
        0.6,
        0.7,
        0.8,
        0.9,
        1.0
      ],
      "tuning_pattern_settings": {
        "diff_pair_defaults": {
          "corner_radius_percentage": 80,
          "corner_style": 1,
          "max_amplitude": 1.0,
          "min_amplitude": 0.2,
          "single_sided": false,
          "spacing": 1.0
        },
        "diff_pair_skew_defaults": {
          "corner_radius_percentage": 80,
          "corner_style": 1,
          "max_amplitude": 1.0,
          "min_amplitude": 0.2,
          "single_sided": false,
          "spacing": 0.6
        },
        "single_track_defaults": {
          "corner_radius_percentage": 80,
          "corner_style": 1,
          "max_amplitude": 1.0,
          "min_amplitude": 0.2,
          "single_sided": false,
          "spacing": 0.6
        }
      },
      "via_dimensions": [
        {
          "diameter": 0.0,
          "drill": 0.0
        },
        {
          "diameter": 0.5,
          "drill": 0.2
        }
      ],
      "zones_allow_external_fillets": true,
      "zones_use_no_outline": true
    },
    "ipc2581": {
      "dist": "",
      "distpn": "",
      "internal_id": "",
      "mfg": "",
      "mpn": ""
    },
    "layer_pairs": [],
    "layer_presets": [],
    "viewports": []
  },
  "boards": [],
  "cvpcb": {
    "equivalence_files": []
  },
  "erc": {
    "erc_exclusions": [],
    "meta": {
      "version": 0
    },
    "pin_map": [
      [
        0,
        0,
        0,
        0,
        0,
        0,
        1,
        0,
        0,
        0,
        0,
        2
      ],
      [
        0,
        2,
        0,
        1,
        0,
        0,
        1,
        0,
        2,
        2,
        2,
        2
      ],
      [
        0,
        0,
        0,
        0,
        0,
        0,
        1,
        0,
        1,
        0,
        1,
        2
      ],
      [
        0,
        1,
        0,
        0,
        0,
        0,
        1,
        1,
        2,
        1,
        1,
        2
      ],
      [
        0,
        0,
        0,
        0,
        0,
        0,
        1,
        0,
        0,
        0,
        0,
        2
      ],
      [
        0,
        0,
        0,
        0,
        0,
        0,
        0,
        0,
        0,
        0,
        0,
        2
      ],
      [
        1,
        1,
        1,
        1,
        1,
        0,
        1,
        1,
        1,
        1,
        1,
        2
      ],
      [
        0,
        0,
        0,
        1,
        0,
        0,
        1,
        0,
        0,
        0,
        0,
        2
      ],
      [
        0,
        2,
        1,
        2,
        0,
        0,
        1,
        0,
        2,
        2,
        2,
        2
      ],
      [
        0,
        2,
        0,
        1,
        0,
        0,
        1,
        0,
        2,
        0,
        0,
        2
      ],
      [
        0,
        2,
        1,
        1,
        0,
        0,
        1,
        0,
        2,
        0,
        0,
        2
      ],
      [
        2,
        2,
        2,
        2,
        2,
        2,
        2,
        2,
        2,
        2,
        2,
        2
      ]
    ],
    "rule_severities": {
      "bus_definition_conflict": "error",
      "bus_entry_needed": "error",
      "bus_to_bus_conflict": "error",
      "bus_to_net_conflict": "error",
      "conflicting_netclasses": "error",
      "different_unit_footprint": "error",
      "different_unit_net": "error",
      "duplicate_reference": "error",
      "duplicate_sheet_names": "error",
      "endpoint_off_grid": "warning",
      "extra_units": "error",
      "footprint_filter": "ignore",
      "footprint_link_issues": "warning",
      "four_way_junction": "ignore",
      "global_label_dangling": "warning",
      "hier_label_mismatch": "error",
      "label_dangling": "error",
      "label_multiple_wires": "warning",
      "lib_symbol_issues": "warning",
      "lib_symbol_mismatch": "warning",
      "missing_bidi_pin": "warning",
      "missing_input_pin": "warning",
      "missing_power_pin": "error",
      "missing_unit": "warning",
      "multiple_net_names": "warning",
      "net_not_bus_member": "warning",
      "no_connect_connected": "warning",
      "no_connect_dangling": "warning",
      "pin_not_connected": "error",
      "pin_not_driven": "error",
      "pin_to_pin": "warning",
      "power_pin_not_driven": "error",
      "same_local_global_label": "warning",
      "similar_label_and_power": "warning",
      "similar_labels": "warning",
      "similar_power": "warning",
      "simulation_model_issue": "ignore",
      "single_global_label": "ignore",
      "unannotated": "error",
      "unconnected_wire_endpoint": "warning",
      "undefined_netclass": "error",
      "unit_value_mismatch": "error",
      "unresolved_variable": "error",
      "wire_dangling": "error"
    }
  },
  "libraries": {
    "pinned_footprint_libs": [],
    "pinned_symbol_libs": []
  },
  "meta": {
    "filename": "lpddr4-test-board.kicad_pro",
    "version": 3
  },
  "net_settings": {
    "classes": [
      {
        "bus_width": 12,
        "clearance": 0.125,
        "diff_pair_gap": 0.2,
        "diff_pair_via_gap": 0.25,
        "diff_pair_width": 0.1,
        "line_style": 0,
        "microvia_diameter": 0.3,
        "microvia_drill": 0.1,
        "name": "Default",
        "pcb_color": "rgba(0, 0, 0, 0.000)",
        "priority": 2147483647,
        "schematic_color": "rgba(0, 0, 0, 0.000)",
        "track_width": 0.1,
        "via_diameter": 0.5,
        "via_drill": 0.2,
        "wire_width": 6
      },
      {
        "bus_width": 12,
        "clearance": 0.125,
        "diff_pair_gap": 0.182,
        "diff_pair_via_gap": 0.25,
        "diff_pair_width": 0.1,
        "line_style": 0,
        "microvia_diameter": 0.3,
        "microvia_drill": 0.1,
        "name": "50Ohm-se_LPDDR4_DQ",
        "pcb_color": "rgba(0, 0, 0, 0.000)",
        "priority": 0,
        "schematic_color": "rgba(0, 0, 0, 0.000)",
        "track_width": 0.182,
        "via_diameter": 0.5,
        "via_drill": 0.2,
        "wire_width": 6
      },
      {
        "bus_width": 12,
        "clearance": 0.125,
        "diff_pair_gap": 0.196,
        "diff_pair_via_gap": 0.25,
        "diff_pair_width": 0.182,
        "line_style": 0,
        "microvia_diameter": 0.3,
        "microvia_drill": 0.1,
        "name": "80Ohm-diff_LPDDR4_DQS",
        "pcb_color": "rgba(0, 0, 0, 0.000)",
        "priority": 1,
        "schematic_color": "rgba(0, 0, 0, 0.000)",
        "track_width": 0.1,
        "via_diameter": 0.5,
        "via_drill": 0.2,
        "wire_width": 6
      },
      {
        "bus_width": 12,
        "clearance": 0.125,
        "diff_pair_gap": 0.2,
        "diff_pair_via_gap": 0.25,
        "diff_pair_width": 0.1,
        "line_style": 0,
        "microvia_diameter": 0.3,
        "microvia_drill": 0.1,
        "name": "USB",
        "pcb_color": "rgba(0, 0, 0, 0.000)",
        "priority": 2,
        "schematic_color": "rgba(0, 0, 0, 0.000)",
        "track_width": 0.15,
        "via_diameter": 0.5,
        "via_drill": 0.2,
        "wire_width": 6
      },
      {
        "bus_width": 12,
        "clearance": 0.125,
        "diff_pair_gap": 0.17,
        "diff_pair_via_gap": 0.25,
        "diff_pair_width": 0.14,
        "line_style": 0,
        "microvia_diameter": 0.3,
        "microvia_drill": 0.1,
        "name": "Z=100",
        "pcb_color": "rgba(0, 0, 0, 0.000)",
        "priority": 3,
        "schematic_color": "rgba(0, 0, 0, 0.000)",
        "track_width": 0.14,
        "via_diameter": 0.5,
        "via_drill": 0.2,
        "wire_width": 6
      }
    ],
    "meta": {
      "version": 4
    },
    "net_colors": null,
    "netclass_assignments": null,
    "netclass_patterns": []
  },
  "pcbnew": {
    "last_paths": {
      "gencad": "",
      "idf": "",
      "netlist": "",
      "plot": "",
      "pos_files": "",
      "specctra_dsn": "",
      "step": "",
      "svg": "",
      "vrml": ""
    },
    "page_layout_descr_file": ""
  },
  "schematic": {
    "annotate_start_num": 0,
    "bom_export_filename": "${PROJECTNAME}.csv",
    "bom_fmt_presets": [],
    "bom_fmt_settings": {
      "field_delimiter": ",",
      "keep_line_breaks": false,
      "keep_tabs": false,
      "name": "CSV",
      "ref_delimiter": ",",
      "ref_range_delimiter": "",
      "string_delimiter": "\""
    },
    "bom_presets": [],
    "bom_settings": {
      "exclude_dnp": false,
      "fields_ordered": [
        {
          "group_by": false,
          "label": "Reference",
          "name": "Reference",
          "show": true
        },
        {
          "group_by": false,
          "label": "Qty",
          "name": "${QUANTITY}",
          "show": true
        },
        {
          "group_by": true,
          "label": "Value",
          "name": "Value",
          "show": true
        },
        {
          "group_by": true,
          "label": "DNP",
          "name": "${DNP}",
          "show": true
        },
        {
          "group_by": true,
          "label": "Exclude from BOM",
          "name": "${EXCLUDE_FROM_BOM}",
          "show": true
        },
        {
          "group_by": true,
          "label": "Exclude from Board",
          "name": "${EXCLUDE_FROM_BOARD}",
          "show": true
        },
        {
          "group_by": true,
          "label": "Footprint",
          "name": "Footprint",
          "show": true
        },
        {
          "group_by": false,
          "label": "Datasheet",
          "name": "Datasheet",
          "show": true
        }
      ],
      "filter_string": "",
      "group_symbols": true,
      "include_excluded_from_bom": true,
      "name": "Default Editing",
      "sort_asc": true,
      "sort_field": "Reference"
    },
    "connection_grid_size": 50.0,
    "drawing": {
      "dashed_lines_dash_length_ratio": 12.0,
      "dashed_lines_gap_length_ratio": 3.0,
      "default_line_thickness": 6.0,
      "default_text_size": 50.0,
      "field_names": [],
      "intersheets_ref_own_page": false,
      "intersheets_ref_prefix": "",
      "intersheets_ref_short": false,
      "intersheets_ref_show": false,
      "intersheets_ref_suffix": "",
      "junction_size_choice": 3,
      "label_size_ratio": 0.25,
      "operating_point_overlay_i_precision": 3,
      "operating_point_overlay_i_range": "~A",
      "operating_point_overlay_v_precision": 3,
      "operating_point_overlay_v_range": "~V",
      "overbar_offset_ratio": 1.23,
      "pin_symbol_size": 0.0,
      "text_offset_ratio": 0.08
    },
    "legacy_lib_dir": "",
    "legacy_lib_list": [],
    "meta": {
      "version": 1
    },
    "net_format_name": "",
    "ngspice": {
      "fix_include_paths": true,
      "fix_passive_vals": false,
      "meta": {
        "version": 0
      },
      "model_mode": 0,
      "workbook_filename": ""
    },
    "page_layout_descr_file": "",
    "plot_directory": "",
    "space_save_all_events": true,
    "spice_adjust_passive_values": false,
    "spice_current_sheet_as_root": false,
    "spice_external_command": "spice \"%I\"",
    "spice_model_current_sheet_as_root": true,
    "spice_save_all_currents": false,
    "spice_save_all_dissipations": false,
    "spice_save_all_voltages": false,
    "subpart_first_id": 65,
    "subpart_id_separator": 0
  },
  "sheets": [
    [
      "",
      "Root"
    ],
    [
      "",
      "HyperRAM"
    ],
    [
      "",
      "FPGA Banks"
    ],
    [
      "",
      "Interfaces"
    ],
    [
      "",
      "Config SPI flash"
    ],
    [
      "",
      "FPGA power"
    ],
    [
      "",
      "Ethernet"
    ],
    [
      "",
      "Supply"
    ],
    [
      "",
      "SO-DIMM"
    ]
  ],
  "text_variables": {}
}
